# T6G (Grand Teton) — schematic netlist excerpt (pin names and nets, part order shuffled) for the footprints in the layout excerpt that follows; sources: Cadence DE-HDL packaged netlist, KiCad conversion of 04192023_DAF0TMB3IC0_F0TG_MB_C_brd_V02_OCP.brd

R4153  Q_RES  10K 1% CHIP  pkg 0402LF  page 125 : A = P3V3_AUX ; B = PRSNT_CABLE_GPU_A1_N

PU6001  MPQ8626GDZ  MPQ8626GD-Z IC  pkg QFN14_0-5_3X2XA  page 270
  PGND1  = GND
  SW1  = SW_P1V2_AUX_PH
  VIN  = SW_P12V_AUX_P1V2_AUX_FLT
  CS  = P1V2_AUX_CS
  EN  = P1V2_AUX_ENABLE
  FB  = P1V2_AUX_FB
  AGND  = GND
  TRK_REF  = P1V2_AUX_REF
  PGOOD  = PWRGD_P1V2_AUX
  BST  = SW_P1V2_AUX_BT
  SW2  = SW_P1V2_AUX_PH
  MODE  = P1V2_AUX_MODE
  VCC  = P1V2_AUX_VCC
  PGND2  = GND

(kicad_pcb
	(version 20260206)
	(generator "pcbnew")
	(generator_version "10.0")
	(general
		(thickness 1.6)
		(legacy_teardrops no)
	)
	(paper "A4")
	(title_block
		(title "04192023_DAF0TMB3IC0_F0TG_MB_C_brd_V02_OCP.brd")
		(comment 1 "Grand Teton / footprints 1193-1194 of 8354")
	)
	(layers
		(0 "F.Cu" signal "TOP")
		(4 "In1.Cu" signal "GND")
		(6 "In2.Cu" signal "IN1")
		(8 "In3.Cu" signal "GND1")
		(10 "In4.Cu" signal "IN2")
		(12 "In5.Cu" signal "GND2")
		(14 "In6.Cu" signal "IN3")
		(16 "In7.Cu" signal "GND3")
		(18 "In8.Cu" signal "VCC")
		(20 "In9.Cu" signal "VCC1")
		(22 "In10.Cu" signal "GND4")
		(24 "In11.Cu" signal "IN4")
		(26 "In12.Cu" signal "GND5")
		(28 "In13.Cu" signal "IN5")
		(30 "In14.Cu" signal "GND6")
		(32 "In15.Cu" signal "IN6")
		(34 "In16.Cu" signal "GND7")
		(2 "B.Cu" signal "BOTTOM")
		(9 "F.Adhes" user "F.Adhesive")
		(11 "B.Adhes" user "B.Adhesive")
		(13 "F.Paste" user "Package Geometry/Pastemask Top")
		(15 "B.Paste" user "Package Geometry/Pastemask Bottom")
		(5 "F.SilkS" user "Ref Des/Silkscreen Top")
		(7 "B.SilkS" user "Ref Des/Silkscreen Bottom")
		(1 "F.Mask" user "Board Geometry/Soldermask Top")
		(3 "B.Mask" user "Board Geometry/Soldermask Bottom")
		(17 "Dwgs.User" user "User.Drawings")
		(19 "Cmts.User" user "User.Comments")
		(21 "Eco1.User" user "User.Eco1")
		(23 "Eco2.User" user "User.Eco2")
		(25 "Edge.Cuts" user "Board Geometry/Outline")
		(27 "Margin" user)
		(31 "F.CrtYd" user "Package Geometry/Place Bound Top")
		(29 "B.CrtYd" user "Package Geometry/Place Bound Bottom")
		(35 "F.Fab" user "Ref Des/Assembly Top")
		(33 "B.Fab" user "Ref Des/Assembly Bottom")
	)
	(footprint ""
		(layer "F.Cu")
		(at 121.36374 -76.001626)
		(property "Reference" "PU6001"
			(at -4.776978 -4.383278 0)
			(unlocked yes)
			(layer "F.SilkS")
			(effects
				(font
					(size 0.7874 0.5842)
					(thickness 0.1524)
				)
				(justify left)
			)
		)
		(property "Value" ""
			(at 0 0 0)
			(layer "F.Fab")
			(effects
				(font
					(size 1.27 1.27)
				)
			)
		)
		(duplicate_pad_numbers_are_jumpers no)
		(fp_line
			(start -1.050036 -1.549908)
			(end -0.503936 -1.549908)
			(stroke
				(width 0.1524)
				(type default)
			)
			(layer "F.SilkS")
		)
		(fp_line
			(start -1.050036 -1.253998)
			(end -1.050036 -1.549908)
			(stroke
				(width 0.1524)
				(type default)
			)
			(layer "F.SilkS")
		)
		(fp_line
			(start -1.050036 1.549908)
			(end -1.050036 1.253998)
			(stroke
				(width 0.1524)
				(type default)
			)
			(layer "F.SilkS")
		)
		(fp_line
			(start -0.503936 1.549908)
			(end -1.050036 1.549908)
			(stroke
				(width 0.1524)
				(type default)
			)
			(layer "F.SilkS")
		)
		(fp_line
			(start 0.503936 -1.549908)
			(end 1.050036 -1.549908)
			(stroke
				(width 0.1524)
				(type default)
			)
			(layer "F.SilkS")
		)
		(fp_line
			(start 1.050036 -1.549908)
			(end 1.050036 -1.253998)
			(stroke
				(width 0.1524)
				(type default)
			)
			(layer "F.SilkS")
		)
		(fp_line
			(start 1.050036 1.253998)
			(end 1.050036 1.549908)
			(stroke
				(width 0.1524)
				(type default)
			)
			(layer "F.SilkS")
		)
		(fp_line
			(start 1.050036 1.549908)
			(end 0.503936 1.549908)
			(stroke
				(width 0.1524)
				(type default)
			)
			(layer "F.SilkS")
		)
		(fp_poly
			(pts
				(xy -1.394968 -1.542034) (xy -2.203196 -1.811528) (xy -1.664208 -2.350262)
			)
			(stroke
				(width 0)
				(type default)
			)
			(fill yes)
			(layer "F.SilkS")
		)
		(fp_line
			(start -1.050036 -1.549908)
			(end 1.050036 -1.549908)
			(stroke
				(width 0.1)
				(type default)
			)
			(layer "F.Fab")
		)
		(fp_line
			(start -1.050036 1.549908)
			(end -1.050036 -1.549908)
			(stroke
				(width 0.1)
				(type default)
			)
			(layer "F.Fab")
		)
		(fp_line
			(start 1.050036 -1.549908)
			(end 1.050036 1.549908)
			(stroke
				(width 0.1)
				(type default)
			)
			(layer "F.Fab")
		)
		(fp_line
			(start 1.050036 1.549908)
			(end -1.050036 1.549908)
			(stroke
				(width 0.1)
				(type default)
			)
			(layer "F.Fab")
		)
		(fp_poly
			(pts
				(xy -2.2352 -0.618998) (xy -2.2352 -1.380998) (xy -1.4732 -0.999998)
			)
			(stroke
				(width 0)
				(type default)
			)
			(fill yes)
			(layer "F.Fab")
		)
		(pad "1" smd circle
			(at -0.94996 -0.999998 270)
			(size 0 0)
			(layers "F.Cu" "F.Mask" "F.Paste")
			(net "GND")
		)
		(pad "2" smd rect
			(at -0.849884 -0.499872 90)
			(size 0.254 0.9144)
			(layers "F.Cu" "F.Mask" "F.Paste")
			(net "SW_P1V2_AUX_PH")
		)
		(pad "3" smd rect
			(at -0.649986 0 90)
			(size 0.254 1.3208)
			(layers "F.Cu" "F.Mask" "F.Paste")
			(net "SW_P12V_AUX_P1V2_AUX_FLT")
		)
		(pad "4" smd rect
			(at -0.849884 0.499872 90)
			(size 0.254 0.9144)
			(layers "F.Cu" "F.Mask" "F.Paste")
			(net "P1V2_AUX_CS")
		)
		(pad "5" smd circle
			(at -0.94996 0.999998 270)
			(size 0 0)
			(layers "F.Cu" "F.Mask" "F.Paste")
			(net "P1V2_AUX_ENABLE")
		)
		(pad "6" smd circle
			(at -0.249936 1.450086)
			(size 0 0)
			(layers "F.Cu" "F.Mask" "F.Paste")
			(net "P1V2_AUX_FB")
		)
		(pad "7" smd circle
			(at 0.249936 1.450086)
			(size 0 0)
			(layers "F.Cu" "F.Mask" "F.Paste")
			(net "GND")
		)
		(pad "8" smd circle
			(at 0.94996 0.999998 90)
			(size 0 0)
			(layers "F.Cu" "F.Mask" "F.Paste")
			(net "P1V2_AUX_REF")
		)
		(pad "9" smd rect
			(at 0.849884 0.499872 90)
			(size 0.254 0.9144)
			(layers "F.Cu" "F.Mask" "F.Paste")
			(net "PWRGD_P1V2_AUX")
		)
		(pad "10" smd rect
			(at 0.849884 0 90)
			(size 0.254 0.9144)
			(layers "F.Cu" "F.Mask" "F.Paste")
			(net "SW_P1V2_AUX_BT")
		)
		(pad "11" smd rect
			(at 0.849884 -0.499872 90)
			(size 0.254 0.9144)
			(layers "F.Cu" "F.Mask" "F.Paste")
			(net "SW_P1V2_AUX_PH")
		)
		(pad "12" smd circle
			(at 0.94996 -0.999998 90)
			(size 0 0)
			(layers "F.Cu" "F.Mask" "F.Paste")
			(net "P1V2_AUX_MODE")
		)
		(pad "13" smd circle
			(at 0.249936 -1.450086 180)
			(size 0 0)
			(layers "F.Cu" "F.Mask" "F.Paste")
			(net "P1V2_AUX_VCC")
		)
		(pad "14" smd circle
			(at -0.249936 -1.450086 180)
			(size 0 0)
			(layers "F.Cu" "F.Mask" "F.Paste")
			(net "GND")
		)
	)
	(footprint ""
		(layer "F.Cu")
		(at 355.506782 -413.046418)
		(property "Reference" "R4153"
			(at 0 0 0)
			(layer "F.SilkS")
			(hide yes)
			(effects
				(font
					(size 1.27 1.27)
				)
			)
		)
		(property "Value" ""
			(at 0 0 0)
			(layer "F.Fab")
			(effects
				(font
					(size 1.27 1.27)
				)
			)
		)
		(duplicate_pad_numbers_are_jumpers no)
		(fp_line
			(start -0.7874 -0.4064)
			(end 0.7874 -0.4064)
			(stroke
				(width 0.1524)
				(type default)
			)
			(layer "F.SilkS")
		)
		(fp_line
			(start -0.7874 0.4064)
			(end -0.7874 -0.4064)
			(stroke
				(width 0.1524)
				(type default)
			)
			(layer "F.SilkS")
		)
		(fp_line
			(start 0.7874 -0.4064)
			(end 0.7874 0.4064)
			(stroke
				(width 0.1524)
				(type default)
			)
			(layer "F.SilkS")
		)
		(fp_line
			(start 0.7874 0.4064)
			(end -0.7874 0.4064)
			(stroke
				(width 0.1524)
				(type default)
			)
			(layer "F.SilkS")
		)
		(fp_line
			(start -0.67945 -0.305054)
			(end -0.12065 -0.305054)
			(stroke
				(width 0.1)
				(type default)
			)
			(layer "F.Fab")
		)
		(fp_line
			(start -0.67945 0.3048)
			(end -0.67945 -0.305054)
			(stroke
				(width 0.1)
				(type default)
			)
			(layer "F.Fab")
		)
		(fp_line
			(start -0.12065 -0.305054)
			(end -0.12065 -0.2794)
			(stroke
				(width 0.1)
				(type default)
			)
			(layer "F.Fab")
		)
		(fp_line
			(start -0.12065 -0.2794)
			(end 0.12065 -0.2794)
			(stroke
				(width 0.1)
				(type default)
			)
			(layer "F.Fab")
		)
		(fp_line
			(start -0.12065 0.2794)
			(end -0.12065 0.3048)
			(stroke
				(width 0.1)
				(type default)
			)
			(layer "F.Fab")
		)
		(fp_line
			(start -0.12065 0.3048)
			(end -0.67945 0.3048)
			(stroke
				(width 0.1)
				(type default)
			)
			(layer "F.Fab")
		)
		(fp_line
			(start 0.120396 0.2794)
			(end -0.12065 0.2794)
			(stroke
				(width 0.1)
				(type default)
			)
			(layer "F.Fab")
		)
		(fp_line
			(start 0.120396 0.3048)
			(end 0.120396 0.2794)
			(stroke
				(width 0.1)
				(type default)
			)
			(layer "F.Fab")
		)
		(fp_line
			(start 0.12065 -0.3048)
			(end 0.67945 -0.3048)
			(stroke
				(width 0.1)
				(type default)
			)
			(layer "F.Fab")
		)
		(fp_line
			(start 0.12065 -0.2794)
			(end 0.12065 -0.3048)
			(stroke
				(width 0.1)
				(type default)
			)
			(layer "F.Fab")
		)
		(fp_line
			(start 0.67945 -0.3048)
			(end 0.67945 0.3048)
			(stroke
				(width 0.1)
				(type default)
			)
			(layer "F.Fab")
		)
		(fp_line
			(start 0.67945 0.3048)
			(end 0.120396 0.3048)
			(stroke
				(width 0.1)
				(type default)
			)
			(layer "F.Fab")
		)
		(pad "1" smd circle
			(at -0.40005 0)
			(size 0 0)
			(layers "F.Cu" "F.Mask" "F.Paste")
			(net "P3V3_AUX")
		)
		(pad "2" smd circle
			(at 0.40005 0)
			(size 0 0)
			(layers "F.Cu" "F.Mask" "F.Paste")
			(net "PRSNT_CABLE_GPU_A1_N")
		)
	)
)
